# T6G (Grand Teton) — schematic netlist excerpt (pin names and nets, part order shuffled) for the footprints in the layout excerpt that follows; sources: Cadence DE-HDL packaged netlist, KiCad conversion of 04192023_DAF0TMB3IC0_F0TG_MB_C_brd_V02_OCP.brd

R804  Q_RES  10K 1% CHIP  pkg 0402LF  page 83 : A = RST_PERST_M2_0_N ; B = GND
D8005  SCHOTTKY_12  B0530WS7F EMPTY  pkg SOD323XB  page 98 : A = PWRGD_CHAF_CPU1_R1 ; C = P3V3_AUX

(kicad_pcb
	(version 20260206)
	(generator "pcbnew")
	(generator_version "10.0")
	(general
		(thickness 1.6)
		(legacy_teardrops no)
	)
	(paper "A4")
	(title_block
		(title "04192023_DAF0TMB3IC0_F0TG_MB_C_brd_V02_OCP.brd")
		(comment 1 "Grand Teton / footprints 4560-4561 of 8354")
	)
	(layers
		(0 "F.Cu" signal "TOP")
		(4 "In1.Cu" signal "GND")
		(6 "In2.Cu" signal "IN1")
		(8 "In3.Cu" signal "GND1")
		(10 "In4.Cu" signal "IN2")
		(12 "In5.Cu" signal "GND2")
		(14 "In6.Cu" signal "IN3")
		(16 "In7.Cu" signal "GND3")
		(18 "In8.Cu" signal "VCC")
		(20 "In9.Cu" signal "VCC1")
		(22 "In10.Cu" signal "GND4")
		(24 "In11.Cu" signal "IN4")
		(26 "In12.Cu" signal "GND5")
		(28 "In13.Cu" signal "IN5")
		(30 "In14.Cu" signal "GND6")
		(32 "In15.Cu" signal "IN6")
		(34 "In16.Cu" signal "GND7")
		(2 "B.Cu" signal "BOTTOM")
		(9 "F.Adhes" user "F.Adhesive")
		(11 "B.Adhes" user "B.Adhesive")
		(13 "F.Paste" user "Package Geometry/Pastemask Top")
		(15 "B.Paste" user "Package Geometry/Pastemask Bottom")
		(5 "F.SilkS" user "Ref Des/Silkscreen Top")
		(7 "B.SilkS" user "Ref Des/Silkscreen Bottom")
		(1 "F.Mask" user "Board Geometry/Soldermask Top")
		(3 "B.Mask" user "Board Geometry/Soldermask Bottom")
		(17 "Dwgs.User" user "User.Drawings")
		(19 "Cmts.User" user "User.Comments")
		(21 "Eco1.User" user "User.Eco1")
		(23 "Eco2.User" user "User.Eco2")
		(25 "Edge.Cuts" user "Board Geometry/Outline")
		(27 "Margin" user)
		(31 "F.CrtYd" user "Package Geometry/Place Bound Top")
		(29 "B.CrtYd" user "Package Geometry/Place Bound Bottom")
		(35 "F.Fab" user "Ref Des/Assembly Top")
		(33 "B.Fab" user "Ref Des/Assembly Bottom")
	)
	(footprint ""
		(layer "F.Cu")
		(at 200.952608 -119.721376)
		(property "Reference" "R804"
			(at 0 0 0)
			(layer "F.SilkS")
			(hide yes)
			(effects
				(font
					(size 1.27 1.27)
				)
			)
		)
		(property "Value" ""
			(at 0 0 0)
			(layer "F.Fab")
			(effects
				(font
					(size 1.27 1.27)
				)
			)
		)
		(duplicate_pad_numbers_are_jumpers no)
		(fp_line
			(start -0.7874 -0.4064)
			(end 0.7874 -0.4064)
			(stroke
				(width 0.1524)
				(type default)
			)
			(layer "F.SilkS")
		)
		(fp_line
			(start -0.7874 0.4064)
			(end -0.7874 -0.4064)
			(stroke
				(width 0.1524)
				(type default)
			)
			(layer "F.SilkS")
		)
		(fp_line
			(start 0.7874 -0.4064)
			(end 0.7874 0.4064)
			(stroke
				(width 0.1524)
				(type default)
			)
			(layer "F.SilkS")
		)
		(fp_line
			(start 0.7874 0.4064)
			(end -0.7874 0.4064)
			(stroke
				(width 0.1524)
				(type default)
			)
			(layer "F.SilkS")
		)
		(fp_line
			(start -0.67945 -0.305054)
			(end -0.12065 -0.305054)
			(stroke
				(width 0.1)
				(type default)
			)
			(layer "F.Fab")
		)
		(fp_line
			(start -0.67945 0.3048)
			(end -0.67945 -0.305054)
			(stroke
				(width 0.1)
				(type default)
			)
			(layer "F.Fab")
		)
		(fp_line
			(start -0.12065 -0.305054)
			(end -0.12065 -0.2794)
			(stroke
				(width 0.1)
				(type default)
			)
			(layer "F.Fab")
		)
		(fp_line
			(start -0.12065 -0.2794)
			(end 0.12065 -0.2794)
			(stroke
				(width 0.1)
				(type default)
			)
			(layer "F.Fab")
		)
		(fp_line
			(start -0.12065 0.2794)
			(end -0.12065 0.3048)
			(stroke
				(width 0.1)
				(type default)
			)
			(layer "F.Fab")
		)
		(fp_line
			(start -0.12065 0.3048)
			(end -0.67945 0.3048)
			(stroke
				(width 0.1)
				(type default)
			)
			(layer "F.Fab")
		)
		(fp_line
			(start 0.120396 0.2794)
			(end -0.12065 0.2794)
			(stroke
				(width 0.1)
				(type default)
			)
			(layer "F.Fab")
		)
		(fp_line
			(start 0.120396 0.3048)
			(end 0.120396 0.2794)
			(stroke
				(width 0.1)
				(type default)
			)
			(layer "F.Fab")
		)
		(fp_line
			(start 0.12065 -0.3048)
			(end 0.67945 -0.3048)
			(stroke
				(width 0.1)
				(type default)
			)
			(layer "F.Fab")
		)
		(fp_line
			(start 0.12065 -0.2794)
			(end 0.12065 -0.3048)
			(stroke
				(width 0.1)
				(type default)
			)
			(layer "F.Fab")
		)
		(fp_line
			(start 0.67945 -0.3048)
			(end 0.67945 0.3048)
			(stroke
				(width 0.1)
				(type default)
			)
			(layer "F.Fab")
		)
		(fp_line
			(start 0.67945 0.3048)
			(end 0.120396 0.3048)
			(stroke
				(width 0.1)
				(type default)
			)
			(layer "F.Fab")
		)
		(pad "1" smd circle
			(at -0.40005 0)
			(size 0 0)
			(layers "F.Cu" "F.Mask" "F.Paste")
			(net "RST_PERST_M2_0_N")
		)
		(pad "2" smd circle
			(at 0.40005 0)
			(size 0 0)
			(layers "F.Cu" "F.Mask" "F.Paste")
			(net "GND")
		)
	)
	(footprint ""
		(layer "F.Cu")
		(at 149.606 -123.444 180)
		(property "Reference" "D8005"
			(at 3.213862 1.346962 0)
			(unlocked yes)
			(layer "F.SilkS")
			(effects
				(font
					(size 0.7874 0.5842)
					(thickness 0.1524)
				)
				(justify left)
			)
		)
		(property "Value" ""
			(at 0 0 180)
			(layer "F.Fab")
			(effects
				(font
					(size 1.27 1.27)
				)
			)
		)
		(duplicate_pad_numbers_are_jumpers no)
		(fp_line
			(start 2.343404 0.6985)
			(end 2.216404 0.6985)
			(stroke
				(width 0.1524)
				(type default)
			)
			(layer "F.SilkS")
		)
		(fp_line
			(start 2.343404 -0.6985)
			(end 2.343404 0.6985)
			(stroke
				(width 0.1524)
				(type default)
			)
			(layer "F.SilkS")
		)
		(fp_line
			(start 2.229104 0.6985)
			(end 2.051304 0.6985)
			(stroke
				(width 0.1524)
				(type default)
			)
			(layer "F.SilkS")
		)
		(fp_line
			(start 2.229104 -0.6985)
			(end 2.229104 0.6985)
			(stroke
				(width 0.1524)
				(type default)
			)
			(layer "F.SilkS")
		)
		(fp_line
			(start 2.152904 0.635)
			(end 2.152904 -0.6985)
			(stroke
				(width 0.1524)
				(type default)
			)
			(layer "F.SilkS")
		)
		(fp_line
			(start 2.152904 -0.6985)
			(end 2.343404 -0.6985)
			(stroke
				(width 0.1524)
				(type default)
			)
			(layer "F.SilkS")
		)
		(fp_line
			(start 2.064004 -0.6731)
			(end 2.064004 -0.6985)
			(stroke
				(width 0.1524)
				(type default)
			)
			(layer "F.SilkS")
		)
		(fp_line
			(start 2.064004 -0.6985)
			(end 2.229104 -0.6985)
			(stroke
				(width 0.1524)
				(type default)
			)
			(layer "F.SilkS")
		)
		(fp_line
			(start 2.051304 0.6985)
			(end 2.051304 0.635)
			(stroke
				(width 0.1524)
				(type default)
			)
			(layer "F.SilkS")
		)
		(fp_line
			(start 2.051304 0.635)
			(end 2.152904 0.635)
			(stroke
				(width 0.1524)
				(type default)
			)
			(layer "F.SilkS")
		)
		(fp_line
			(start 2.050796 0.700024)
			(end -2.050796 0.700024)
			(stroke
				(width 0.1524)
				(type default)
			)
			(layer "F.SilkS")
		)
		(fp_line
			(start 2.050796 -0.700024)
			(end 2.050796 0.700024)
			(stroke
				(width 0.1524)
				(type default)
			)
			(layer "F.SilkS")
		)
		(fp_line
			(start 0.293878 -0.500126)
			(end 0.293878 0.500126)
			(stroke
				(width 0.1524)
				(type default)
			)
			(layer "F.SilkS")
		)
		(fp_line
			(start 0.193802 0)
			(end -0.30607 -0.500126)
			(stroke
				(width 0.1524)
				(type default)
			)
			(layer "F.SilkS")
		)
		(fp_line
			(start -0.30607 0.500126)
			(end 0.193802 0)
			(stroke
				(width 0.1524)
				(type default)
			)
			(layer "F.SilkS")
		)
		(fp_line
			(start -0.30607 -0.500126)
			(end -0.30607 0.500126)
			(stroke
				(width 0.1524)
				(type default)
			)
			(layer "F.SilkS")
		)
		(fp_line
			(start -2.050796 0.700024)
			(end -2.050796 -0.700024)
			(stroke
				(width 0.1524)
				(type default)
			)
			(layer "F.SilkS")
		)
		(fp_line
			(start -2.050796 -0.700024)
			(end 2.050796 -0.700024)
			(stroke
				(width 0.1524)
				(type default)
			)
			(layer "F.SilkS")
		)
		(fp_line
			(start 0.899922 0.700024)
			(end -0.899922 0.700024)
			(stroke
				(width 0.1)
				(type default)
			)
			(layer "F.Fab")
		)
		(fp_line
			(start 0.899922 -0.700024)
			(end 0.899922 0.700024)
			(stroke
				(width 0.1)
				(type default)
			)
			(layer "F.Fab")
		)
		(fp_line
			(start -0.899922 0.700024)
			(end -0.899922 -0.700024)
			(stroke
				(width 0.1)
				(type default)
			)
			(layer "F.Fab")
		)
		(fp_line
			(start -0.899922 -0.700024)
			(end 0.899922 -0.700024)
			(stroke
				(width 0.1)
				(type default)
			)
			(layer "F.Fab")
		)
		(fp_text user "-"
			(at 3.880104 0.23495 0)
			(unlocked yes)
			(layer "F.SilkS")
			(effects
				(font
					(size 1.905 1.4224)
					(thickness 0.1524)
				)
				(justify left)
			)
		)
		(fp_text user "+"
			(at -3.362706 1.093978 270)
			(unlocked yes)
			(layer "F.SilkS")
			(effects
				(font
					(size 1.905 1.4224)
					(thickness 0.1524)
				)
				(justify left)
			)
		)
		(fp_text user "-"
			(at 3.880104 0.23495 0)
			(unlocked yes)
			(layer "F.Fab")
			(effects
				(font
					(size 1.905 1.4224)
					(thickness 0.1524)
				)
				(justify left)
			)
		)
		(fp_text user "+"
			(at -3.123946 0.762 270)
			(unlocked yes)
			(layer "F.Fab")
			(effects
				(font
					(size 1.905 1.4224)
					(thickness 0.1524)
				)
				(justify left)
			)
		)
		(pad "1" smd rect
			(at -1.199896 0 90)
			(size 0.6604 1.3716)
			(layers "F.Cu" "F.Mask" "F.Paste")
			(net "PWRGD_CHAF_CPU1_R1")
		)
		(pad "2" smd rect
			(at 1.199896 0 270)
			(size 0.6604 1.3716)
			(layers "F.Cu" "F.Mask" "F.Paste")
			(net "P3V3_AUX")
		)
	)
)
